FILE_TYPE=LIBRARY_PARTS;
primitive 'SCONN80_E67482007','SCONN80_E67482007_SM';
  pin
    'IO1':
      PIN_NUMBER='(1)';
      BIDIRECTIONAL='TRUE';
      INPUT_LOAD='(-0.01,0.01)';
      OUTPUT_LOAD='(1.0,-1.0)';
    'IO10':
      PIN_NUMBER='(10)';
      BIDIRECTIONAL='TRUE';
      INPUT_LOAD='(-0.01,0.01)';
      OUTPUT_LOAD='(1.0,-1.0)';
    'IO11':
      PIN_NUMBER='(11)';
      BIDIRECTIONAL='TRUE';
      INPUT_LOAD='(-0.01,0.01)';
      OUTPUT_LOAD='(1.0,-1.0)';
    'IO12':
      PIN_NUMBER='(12)';
      BIDIRECTIONAL='TRUE';
      INPUT_LOAD='(-0.01,0.01)';
      OUTPUT_LOAD='(1.0,-1.0)';
    'IO13':
      PIN_NUMBER='(13)';
      BIDIRECTIONAL='TRUE';
      INPUT_LOAD='(-0.01,0.01)';
      OUTPUT_LOAD='(1.0,-1.0)';
    'IO14':
      PIN_NUMBER='(14)';
      BIDIRECTIONAL='TRUE';
      INPUT_LOAD='(-0.01,0.01)';
      OUTPUT_LOAD='(1.0,-1.0)';
    'IO15':
      PIN_NUMBER='(15)';
      BIDIRECTIONAL='TRUE';
      INPUT_LOAD='(-0.01,0.01)';
      OUTPUT_LOAD='(1.0,-1.0)';
    'IO16':
      PIN_NUMBER='(16)';
      BIDIRECTIONAL='TRUE';
      INPUT_LOAD='(-0.01,0.01)';
      OUTPUT_LOAD='(1.0,-1.0)';
    'IO17':
      PIN_NUMBER='(17)';
      BIDIRECTIONAL='TRUE';
      INPUT_LOAD='(-0.01,0.01)';
      OUTPUT_LOAD='(1.0,-1.0)';
    'IO18':
      PIN_NUMBER='(18)';
      BIDIRECTIONAL='TRUE';
      INPUT_LOAD='(-0.01,0.01)';
      OUTPUT_LOAD='(1.0,-1.0)';
    'IO19':
      PIN_NUMBER='(19)';
      BIDIRECTIONAL='TRUE';
      INPUT_LOAD='(-0.01,0.01)';
      OUTPUT_LOAD='(1.0,-1.0)';
    'IO2':
      PIN_NUMBER='(2)';
      BIDIRECTIONAL='TRUE';
      INPUT_LOAD='(-0.01,0.01)';
      OUTPUT_LOAD='(1.0,-1.0)';
    'IO20':
      PIN_NUMBER='(20)';
      BIDIRECTIONAL='TRUE';
      INPUT_LOAD='(-0.01,0.01)';
      OUTPUT_LOAD='(1.0,-1.0)';
    'IO21':
      PIN_NUMBER='(21)';
      BIDIRECTIONAL='TRUE';
      INPUT_LOAD='(-0.01,0.01)';
      OUTPUT_LOAD='(1.0,-1.0)';
    'IO22':
      PIN_NUMBER='(22)';
      BIDIRECTIONAL='TRUE';
      INPUT_LOAD='(-0.01,0.01)';
      OUTPUT_LOAD='(1.0,-1.0)';
    'IO23':
      PIN_NUMBER='(23)';
      BIDIRECTIONAL='TRUE';
      INPUT_LOAD='(-0.01,0.01)';
      OUTPUT_LOAD='(1.0,-1.0)';
    'IO24':
      PIN_NUMBER='(24)';
      BIDIRECTIONAL='TRUE';
      INPUT_LOAD='(-0.01,0.01)';
      OUTPUT_LOAD='(1.0,-1.0)';
    'IO25':
      PIN_NUMBER='(25)';
      BIDIRECTIONAL='TRUE';
      INPUT_LOAD='(-0.01,0.01)';
      OUTPUT_LOAD='(1.0,-1.0)';
    'IO26':
      PIN_NUMBER='(26)';
      BIDIRECTIONAL='TRUE';
      INPUT_LOAD='(-0.01,0.01)';
      OUTPUT_LOAD='(1.0,-1.0)';
    'IO27':
      PIN_NUMBER='(27)';
      BIDIRECTIONAL='TRUE';
      INPUT_LOAD='(-0.01,0.01)';
      OUTPUT_LOAD='(1.0,-1.0)';
    'IO28':
      PIN_NUMBER='(28)';
      BIDIRECTIONAL='TRUE';
      INPUT_LOAD='(-0.01,0.01)';
      OUTPUT_LOAD='(1.0,-1.0)';
    'IO29':
      PIN_NUMBER='(29)';
      BIDIRECTIONAL='TRUE';
      INPUT_LOAD='(-0.01,0.01)';
      OUTPUT_LOAD='(1.0,-1.0)';
    'IO3':
      PIN_NUMBER='(3)';
      BIDIRECTIONAL='TRUE';
      INPUT_LOAD='(-0.01,0.01)';
      OUTPUT_LOAD='(1.0,-1.0)';
    'IO30':
      PIN_NUMBER='(30)';
      BIDIRECTIONAL='TRUE';
      INPUT_LOAD='(-0.01,0.01)';
      OUTPUT_LOAD='(1.0,-1.0)';
    'IO31':
      PIN_NUMBER='(31)';
      BIDIRECTIONAL='TRUE';
      INPUT_LOAD='(-0.01,0.01)';
      OUTPUT_LOAD='(1.0,-1.0)';
    'IO32':
      PIN_NUMBER='(32)';
      BIDIRECTIONAL='TRUE';
      INPUT_LOAD='(-0.01,0.01)';
      OUTPUT_LOAD='(1.0,-1.0)';
    'IO33':
      PIN_NUMBER='(33)';
      BIDIRECTIONAL='TRUE';
      INPUT_LOAD='(-0.01,0.01)';
      OUTPUT_LOAD='(1.0,-1.0)';
    'IO34':
      PIN_NUMBER='(34)';
      BIDIRECTIONAL='TRUE';
      INPUT_LOAD='(-0.01,0.01)';
      OUTPUT_LOAD='(1.0,-1.0)';
    'IO35':
      PIN_NUMBER='(35)';
      BIDIRECTIONAL='TRUE';
      INPUT_LOAD='(-0.01,0.01)';
      OUTPUT_LOAD='(1.0,-1.0)';
    'IO36':
      PIN_NUMBER='(36)';
      BIDIRECTIONAL='TRUE';
      INPUT_LOAD='(-0.01,0.01)';
      OUTPUT_LOAD='(1.0,-1.0)';
    'IO37':
      PIN_NUMBER='(37)';
      BIDIRECTIONAL='TRUE';
      INPUT_LOAD='(-0.01,0.01)';
      OUTPUT_LOAD='(1.0,-1.0)';
    'IO38':
      PIN_NUMBER='(38)';
      BIDIRECTIONAL='TRUE';
      INPUT_LOAD='(-0.01,0.01)';
      OUTPUT_LOAD='(1.0,-1.0)';
    'IO39':
      PIN_NUMBER='(39)';
      BIDIRECTIONAL='TRUE';
      INPUT_LOAD='(-0.01,0.01)';
      OUTPUT_LOAD='(1.0,-1.0)';
    'IO4':
      PIN_NUMBER='(4)';
      BIDIRECTIONAL='TRUE';
      INPUT_LOAD='(-0.01,0.01)';
      OUTPUT_LOAD='(1.0,-1.0)';
    'IO40':
      PIN_NUMBER='(40)';
      BIDIRECTIONAL='TRUE';
      INPUT_LOAD='(-0.01,0.01)';
      OUTPUT_LOAD='(1.0,-1.0)';
    'IO41':
      PIN_NUMBER='(41)';
      BIDIRECTIONAL='TRUE';
      INPUT_LOAD='(-0.01,0.01)';
      OUTPUT_LOAD='(1.0,-1.0)';
    'IO42':
      PIN_NUMBER='(42)';
      BIDIRECTIONAL='TRUE';
      INPUT_LOAD='(-0.01,0.01)';
      OUTPUT_LOAD='(1.0,-1.0)';
    'IO43':
      PIN_NUMBER='(43)';
      BIDIRECTIONAL='TRUE';
      INPUT_LOAD='(-0.01,0.01)';
      OUTPUT_LOAD='(1.0,-1.0)';
    'IO44':
      PIN_NUMBER='(44)';
      BIDIRECTIONAL='TRUE';
      INPUT_LOAD='(-0.01,0.01)';
      OUTPUT_LOAD='(1.0,-1.0)';
    'IO45':
      PIN_NUMBER='(45)';
      BIDIRECTIONAL='TRUE';
      INPUT_LOAD='(-0.01,0.01)';
      OUTPUT_LOAD='(1.0,-1.0)';
    'IO46':
      PIN_NUMBER='(46)';
      BIDIRECTIONAL='TRUE';
      INPUT_LOAD='(-0.01,0.01)';
      OUTPUT_LOAD='(1.0,-1.0)';
    'IO47':
      PIN_NUMBER='(47)';
      BIDIRECTIONAL='TRUE';
      INPUT_LOAD='(-0.01,0.01)';
      OUTPUT_LOAD='(1.0,-1.0)';
    'IO48':
      PIN_NUMBER='(48)';
      BIDIRECTIONAL='TRUE';
      INPUT_LOAD='(-0.01,0.01)';
      OUTPUT_LOAD='(1.0,-1.0)';
    'IO49':
      PIN_NUMBER='(49)';
      BIDIRECTIONAL='TRUE';
      INPUT_LOAD='(-0.01,0.01)';
      OUTPUT_LOAD='(1.0,-1.0)';
    'IO5':
      PIN_NUMBER='(5)';
      BIDIRECTIONAL='TRUE';
      INPUT_LOAD='(-0.01,0.01)';
      OUTPUT_LOAD='(1.0,-1.0)';
    'IO50':
      PIN_NUMBER='(50)';
      BIDIRECTIONAL='TRUE';
      INPUT_LOAD='(-0.01,0.01)';
      OUTPUT_LOAD='(1.0,-1.0)';
    'IO51':
      PIN_NUMBER='(51)';
      BIDIRECTIONAL='TRUE';
      INPUT_LOAD='(-0.01,0.01)';
      OUTPUT_LOAD='(1.0,-1.0)';
    'IO52':
      PIN_NUMBER='(52)';
      BIDIRECTIONAL='TRUE';
      INPUT_LOAD='(-0.01,0.01)';
      OUTPUT_LOAD='(1.0,-1.0)';
    'IO53':
      PIN_NUMBER='(53)';
      BIDIRECTIONAL='TRUE';
      INPUT_LOAD='(-0.01,0.01)';
      OUTPUT_LOAD='(1.0,-1.0)';
    'IO54':
      PIN_NUMBER='(54)';
      BIDIRECTIONAL='TRUE';
      INPUT_LOAD='(-0.01,0.01)';
      OUTPUT_LOAD='(1.0,-1.0)';
    'IO55':
      PIN_NUMBER='(55)';
      BIDIRECTIONAL='TRUE';
      INPUT_LOAD='(-0.01,0.01)';
      OUTPUT_LOAD='(1.0,-1.0)';
    'IO56':
      PIN_NUMBER='(56)';
      BIDIRECTIONAL='TRUE';
      INPUT_LOAD='(-0.01,0.01)';
      OUTPUT_LOAD='(1.0,-1.0)';
    'IO57':
      PIN_NUMBER='(57)';
      BIDIRECTIONAL='TRUE';
      INPUT_LOAD='(-0.01,0.01)';
      OUTPUT_LOAD='(1.0,-1.0)';
    'IO58':
      PIN_NUMBER='(58)';
      BIDIRECTIONAL='TRUE';
      INPUT_LOAD='(-0.01,0.01)';
      OUTPUT_LOAD='(1.0,-1.0)';
    'IO59':
      PIN_NUMBER='(59)';
      BIDIRECTIONAL='TRUE';
      INPUT_LOAD='(-0.01,0.01)';
      OUTPUT_LOAD='(1.0,-1.0)';
    'IO6':
      PIN_NUMBER='(6)';
      BIDIRECTIONAL='TRUE';
      INPUT_LOAD='(-0.01,0.01)';
      OUTPUT_LOAD='(1.0,-1.0)';
    'IO60':
      PIN_NUMBER='(60)';
      BIDIRECTIONAL='TRUE';
      INPUT_LOAD='(-0.01,0.01)';
      OUTPUT_LOAD='(1.0,-1.0)';
    'IO61':
      PIN_NUMBER='(61)';
      BIDIRECTIONAL='TRUE';
      INPUT_LOAD='(-0.01,0.01)';
      OUTPUT_LOAD='(1.0,-1.0)';
    'IO62':
      PIN_NUMBER='(62)';
      BIDIRECTIONAL='TRUE';
      INPUT_LOAD='(-0.01,0.01)';
      OUTPUT_LOAD='(1.0,-1.0)';
    'IO63':
      PIN_NUMBER='(63)';
      BIDIRECTIONAL='TRUE';
      INPUT_LOAD='(-0.01,0.01)';
      OUTPUT_LOAD='(1.0,-1.0)';
    'IO64':
      PIN_NUMBER='(64)';
      BIDIRECTIONAL='TRUE';
      INPUT_LOAD='(-0.01,0.01)';
      OUTPUT_LOAD='(1.0,-1.0)';
    'IO65':
      PIN_NUMBER='(65)';
      BIDIRECTIONAL='TRUE';
      INPUT_LOAD='(-0.01,0.01)';
      OUTPUT_LOAD='(1.0,-1.0)';
    'IO66':
      PIN_NUMBER='(66)';
      BIDIRECTIONAL='TRUE';
      INPUT_LOAD='(-0.01,0.01)';
      OUTPUT_LOAD='(1.0,-1.0)';
    'IO67':
      PIN_NUMBER='(67)';
      BIDIRECTIONAL='TRUE';
      INPUT_LOAD='(-0.01,0.01)';
      OUTPUT_LOAD='(1.0,-1.0)';
    'IO68':
      PIN_NUMBER='(68)';
      BIDIRECTIONAL='TRUE';
      INPUT_LOAD='(-0.01,0.01)';
      OUTPUT_LOAD='(1.0,-1.0)';
    'IO69':
      PIN_NUMBER='(69)';
      BIDIRECTIONAL='TRUE';
      INPUT_LOAD='(-0.01,0.01)';
      OUTPUT_LOAD='(1.0,-1.0)';
    'IO7':
      PIN_NUMBER='(7)';
      BIDIRECTIONAL='TRUE';
      INPUT_LOAD='(-0.01,0.01)';
      OUTPUT_LOAD='(1.0,-1.0)';
    'IO70':
      PIN_NUMBER='(70)';
      BIDIRECTIONAL='TRUE';
      INPUT_LOAD='(-0.01,0.01)';
      OUTPUT_LOAD='(1.0,-1.0)';
    'IO71':
      PIN_NUMBER='(71)';
      BIDIRECTIONAL='TRUE';
      INPUT_LOAD='(-0.01,0.01)';
      OUTPUT_LOAD='(1.0,-1.0)';
    'IO72':
      PIN_NUMBER='(72)';
      BIDIRECTIONAL='TRUE';
      INPUT_LOAD='(-0.01,0.01)';
      OUTPUT_LOAD='(1.0,-1.0)';
    'IO73':
      PIN_NUMBER='(73)';
      BIDIRECTIONAL='TRUE';
      INPUT_LOAD='(-0.01,0.01)';
      OUTPUT_LOAD='(1.0,-1.0)';
    'IO74':
      PIN_NUMBER='(74)';
      BIDIRECTIONAL='TRUE';
      INPUT_LOAD='(-0.01,0.01)';
      OUTPUT_LOAD='(1.0,-1.0)';
    'IO75':
      PIN_NUMBER='(75)';
      BIDIRECTIONAL='TRUE';
      INPUT_LOAD='(-0.01,0.01)';
      OUTPUT_LOAD='(1.0,-1.0)';
    'IO76':
      PIN_NUMBER='(76)';
      BIDIRECTIONAL='TRUE';
      INPUT_LOAD='(-0.01,0.01)';
      OUTPUT_LOAD='(1.0,-1.0)';
    'IO77':
      PIN_NUMBER='(77)';
      BIDIRECTIONAL='TRUE';
      INPUT_LOAD='(-0.01,0.01)';
      OUTPUT_LOAD='(1.0,-1.0)';
    'IO78':
      PIN_NUMBER='(78)';
      BIDIRECTIONAL='TRUE';
      INPUT_LOAD='(-0.01,0.01)';
      OUTPUT_LOAD='(1.0,-1.0)';
    'IO79':
      PIN_NUMBER='(79)';
      BIDIRECTIONAL='TRUE';
      INPUT_LOAD='(-0.01,0.01)';
      OUTPUT_LOAD='(1.0,-1.0)';
    'IO8':
      PIN_NUMBER='(8)';
      BIDIRECTIONAL='TRUE';
      INPUT_LOAD='(-0.01,0.01)';
      OUTPUT_LOAD='(1.0,-1.0)';
    'IO80':
      PIN_NUMBER='(80)';
      BIDIRECTIONAL='TRUE';
      INPUT_LOAD='(-0.01,0.01)';
      OUTPUT_LOAD='(1.0,-1.0)';
    'IO9':
      PIN_NUMBER='(9)';
      BIDIRECTIONAL='TRUE';
      INPUT_LOAD='(-0.01,0.01)';
      OUTPUT_LOAD='(1.0,-1.0)';
  end_pin;
  body
    PART_NAME='SCONN80_E67482007';
    PHYS_DES_PREFIX='J';
  end_body;
end_primitive;

END.
